(kicad_pcb
	(version 20241229)
	(generator "pcbnew")
	(generator_version "9.0")
	(general
		(thickness 1.63)
		(legacy_teardrops no)
	)
	(paper "A4")
	(title_block
		(title "CM4 Baseboard")
		(date "2026-01-05")
		(rev "1.1.1")
		(company "Antmicro Ltd")
		(comment 1 "www.antmicro.com")
		(comment 9 "footprints 151-155 of 506")
	)
	(layers
		(0 "F.Cu" signal)
		(4 "In1.Cu" power)
		(6 "In2.Cu" power)
		(8 "In3.Cu" signal)
		(10 "In4.Cu" signal)
		(2 "B.Cu" signal)
		(9 "F.Adhes" user "F.Adhesive")
		(11 "B.Adhes" user "B.Adhesive")
		(13 "F.Paste" user)
		(15 "B.Paste" user)
		(5 "F.SilkS" user "F.Silkscreen")
		(7 "B.SilkS" user "B.Silkscreen")
		(1 "F.Mask" user)
		(3 "B.Mask" user)
		(17 "Dwgs.User" user "User.Drawings")
		(19 "Cmts.User" user "User.Comments")
		(21 "Eco1.User" user "User.Eco1")
		(23 "Eco2.User" user "User.Eco2")
		(25 "Edge.Cuts" user)
		(27 "Margin" user)
		(31 "F.CrtYd" user "F.Courtyard")
		(29 "B.CrtYd" user "B.Courtyard")
		(35 "F.Fab" user)
		(33 "B.Fab" user)
	)
	(footprint "antmicro-footprints:C_0402_1005Metric"
		(layer "F.Cu")
		(at 65.092962 177.7005 -90)
		(descr "Capacitor SMD 0402")
		(tags "capacitor SMD 0402")
		(property "Reference" "C818"
			(at -2.704 13.955 90)
			(layer "F.SilkS")
			(effects
				(font
					(size 0.7 0.7)
					(thickness 0.15)
				)
				(justify right bottom)
			)
		)
		(property "Value" "C_470p_100V_0402"
			(at -1.022927 2.155213 90)
			(layer "F.Fab")
			(effects
				(font
					(size 0.7 0.7)
					(thickness 0.15)
				)
				(justify right bottom)
			)
		)
		(property "Datasheet" "https://search.murata.co.jp/Ceramy/image/img/A01X/G101/ENG/GRM1555C2A471JE01-01A.pdf"
			(at 0 0 270)
			(layer "F.Fab")
			(hide yes)
			(effects
				(font
					(size 1.27 1.27)
					(thickness 0.15)
				)
			)
		)
		(property "Description" "MLCC, SMD/SMT, 100V, 470pF, C0G/NP0, 0402 5%"
			(at 0 0 270)
			(layer "F.Fab")
			(hide yes)
			(effects
				(font
					(size 1.27 1.27)
					(thickness 0.15)
				)
			)
		)
		(property "MPN" "GRM1555C2A471JE01D"
			(at 0 0 270)
			(unlocked yes)
			(layer "F.Fab")
			(hide yes)
			(effects
				(font
					(size 1 1)
					(thickness 0.15)
				)
			)
		)
		(property "Manufacturer" "Murata"
			(at 0 0 270)
			(unlocked yes)
			(layer "F.Fab")
			(hide yes)
			(effects
				(font
					(size 1 1)
					(thickness 0.15)
				)
			)
		)
		(property "License" "Apache-2.0"
			(at 0 0 270)
			(unlocked yes)
			(layer "F.Fab")
			(hide yes)
			(effects
				(font
					(size 1 1)
					(thickness 0.15)
				)
			)
		)
		(property "Author" "Antmicro"
			(at 0 0 270)
			(unlocked yes)
			(layer "F.Fab")
			(hide yes)
			(effects
				(font
					(size 1 1)
					(thickness 0.15)
				)
			)
		)
		(property "Val" "470p"
			(at 0 0 270)
			(unlocked yes)
			(layer "F.Fab")
			(hide yes)
			(effects
				(font
					(size 1 1)
					(thickness 0.15)
				)
			)
		)
		(property "Voltage" "100V"
			(at 0 0 270)
			(unlocked yes)
			(layer "F.Fab")
			(hide yes)
			(effects
				(font
					(size 1 1)
					(thickness 0.15)
				)
			)
		)
		(property "Dielectric" "C0G/NP0"
			(at 0 0 270)
			(unlocked yes)
			(layer "F.Fab")
			(hide yes)
			(effects
				(font
					(size 1 1)
					(thickness 0.15)
				)
			)
		)
		(sheetname "/Peripherals/")
		(sheetfile "peripherals.kicad_sch")
		(attr smd)
		(fp_rect
			(start -0.925 -0.47)
			(end 0.925 0.47)
			(stroke
				(width 0.05)
				(type default)
			)
			(fill no)
			(layer "F.CrtYd")
		)
		(fp_line
			(start -0.494 0.248)
			(end -0.494 -0.25)
			(stroke
				(width 0.15)
				(type solid)
			)
			(layer "F.Fab")
		)
		(fp_line
			(start 0.504 0.248)
			(end -0.494 0.248)
			(stroke
				(width 0.15)
				(type solid)
			)
			(layer "F.Fab")
		)
		(fp_line
			(start -0.494 -0.25)
			(end 0.504 -0.25)
			(stroke
				(width 0.15)
				(type solid)
			)
			(layer "F.Fab")
		)
		(fp_line
			(start 0.504 -0.25)
			(end 0.504 0.248)
			(stroke
				(width 0.15)
				(type solid)
			)
			(layer "F.Fab")
		)
		(fp_text user "${REFERENCE}"
			(at -0.939 4.599 270)
			(layer "F.Fab")
			(effects
				(font
					(size 0.7 0.7)
					(thickness 0.15)
				)
				(justify left bottom)
			)
		)
		(fp_text user "License: Apache-2.0"
			(at -0.939 5.799 270)
			(layer "F.Fab")
			(effects
				(font
					(size 0.7 0.7)
					(thickness 0.15)
				)
				(justify left bottom)
			)
		)
		(fp_text user "Author: Antmicro"
			(at -0.939 3.399 270)
			(layer "F.Fab")
			(effects
				(font
					(size 0.7 0.7)
					(thickness 0.15)
				)
				(justify left bottom)
			)
		)
		(pad "1" smd roundrect
			(at -0.48 0 270)
			(size 0.59 0.64)
			(layers "F.Cu" "F.Mask" "F.Paste")
			(roundrect_rratio 0.25)
			(net 3 "GND")
			(pintype "passive")
		)
		(pad "2" smd roundrect
			(at 0.48 0 270)
			(size 0.59 0.64)
			(layers "F.Cu" "F.Mask" "F.Paste")
			(roundrect_rratio 0.25)
			(net 109 "Net-(C816-Pad2)")
			(pintype "passive")
		)
	)
	(footprint "antmicro-footprints:C_0402_1005Metric"
		(layer "F.Cu")
		(at 100.387962 123.6065)
		(descr "Capacitor SMD 0402")
		(tags "capacitor SMD 0402")
		(property "Reference" "C928"
			(at 0.87 0.67 0)
			(layer "F.SilkS")
			(effects
				(font
					(size 0.7 0.7)
					(thickness 0.15)
				)
				(justify left bottom)
			)
		)
		(property "Value" "C_100n_0402"
			(at -1.022927 2.155213 0)
			(layer "F.Fab")
			(effects
				(font
					(size 0.7 0.7)
					(thickness 0.15)
				)
				(justify left bottom)
			)
		)
		(property "Datasheet" "https://www.murata.com/products/productdetail?partno=GRM155R61H104KE14%23"
			(at 0 0 0)
			(layer "F.Fab")
			(hide yes)
			(effects
				(font
					(size 1.27 1.27)
					(thickness 0.15)
				)
			)
		)
		(property "Manufacturer" "Murata"
			(at 0 0 0)
			(unlocked yes)
			(layer "F.Fab")
			(hide yes)
			(effects
				(font
					(size 1 1)
					(thickness 0.15)
				)
			)
		)
		(property "MPN" "GRM155R61H104KE14D"
			(at 0 0 0)
			(unlocked yes)
			(layer "F.Fab")
			(hide yes)
			(effects
				(font
					(size 1 1)
					(thickness 0.15)
				)
			)
		)
		(property "Val" "100n"
			(at 0 0 0)
			(unlocked yes)
			(layer "F.Fab")
			(hide yes)
			(effects
				(font
					(size 1 1)
					(thickness 0.15)
				)
			)
		)
		(property "License" "Apache-2.0"
			(at 0 0 0)
			(unlocked yes)
			(layer "F.Fab")
			(hide yes)
			(effects
				(font
					(size 1 1)
					(thickness 0.15)
				)
			)
		)
		(property "Author" "Antmicro"
			(at 0 0 0)
			(unlocked yes)
			(layer "F.Fab")
			(hide yes)
			(effects
				(font
					(size 1 1)
					(thickness 0.15)
				)
			)
		)
		(property "Voltage" "50V"
			(at 0 0 0)
			(unlocked yes)
			(layer "F.Fab")
			(hide yes)
			(effects
				(font
					(size 1 1)
					(thickness 0.15)
				)
			)
		)
		(property "Dielectric" "X5R"
			(at 0 0 0)
			(unlocked yes)
			(layer "F.Fab")
			(hide yes)
			(effects
				(font
					(size 1 1)
					(thickness 0.15)
				)
			)
		)
		(sheetname "/USB/")
		(sheetfile "usb.kicad_sch")
		(attr smd)
		(fp_rect
			(start -0.925 -0.47)
			(end 0.925 0.47)
			(stroke
				(width 0.05)
				(type default)
			)
			(fill no)
			(layer "F.CrtYd")
		)
		(fp_line
			(start -0.494 -0.25)
			(end 0.504 -0.25)
			(stroke
				(width 0.15)
				(type solid)
			)
			(layer "F.Fab")
		)
		(fp_line
			(start -0.494 0.248)
			(end -0.494 -0.25)
			(stroke
				(width 0.15)
				(type solid)
			)
			(layer "F.Fab")
		)
		(fp_line
			(start 0.504 -0.25)
			(end 0.504 0.248)
			(stroke
				(width 0.15)
				(type solid)
			)
			(layer "F.Fab")
		)
		(fp_line
			(start 0.504 0.248)
			(end -0.494 0.248)
			(stroke
				(width 0.15)
				(type solid)
			)
			(layer "F.Fab")
		)
		(fp_text user "Author: Antmicro"
			(at -0.939 3.399 0)
			(layer "F.Fab")
			(effects
				(font
					(size 0.7 0.7)
					(thickness 0.15)
				)
				(justify left bottom)
			)
		)
		(fp_text user "License: Apache-2.0"
			(at -0.939 5.799 0)
			(layer "F.Fab")
			(effects
				(font
					(size 0.7 0.7)
					(thickness 0.15)
				)
				(justify left bottom)
			)
		)
		(fp_text user "${REFERENCE}"
			(at -0.939 4.599 0)
			(layer "F.Fab")
			(effects
				(font
					(size 0.7 0.7)
					(thickness 0.15)
				)
				(justify left bottom)
			)
		)
		(pad "1" smd roundrect
			(at -0.48 0)
			(size 0.59 0.64)
			(layers "F.Cu" "F.Mask" "F.Paste")
			(roundrect_rratio 0.25)
			(net 28 "/USB/+5V_{CAP}")
			(pintype "passive")
		)
		(pad "2" smd roundrect
			(at 0.48 0)
			(size 0.59 0.64)
			(layers "F.Cu" "F.Mask" "F.Paste")
			(roundrect_rratio 0.25)
			(net 3 "GND")
			(pintype "passive")
		)
	)
	(footprint "antmicro-footprints:R_0402_1005Metric"
		(layer "F.Cu")
		(at 83.092962 148.5415 180)
		(descr "Resistor SMD 0402")
		(tags "resistor SMD 0402")
		(property "Reference" "R205"
			(at -1.575 0.475 0)
			(layer "F.SilkS")
			(effects
				(font
					(size 0.7 0.7)
					(thickness 0.15)
				)
				(justify right bottom)
			)
		)
		(property "Value" "R_0R_0402"
			(at -1.011843 1.772047 0)
			(layer "F.Fab")
			(effects
				(font
					(size 0.7 0.7)
					(thickness 0.15)
				)
				(justify right bottom)
			)
		)
		(property "Datasheet" "https://industrial.panasonic.com/cdbs/www-data/pdf/RDA0000/AOA0000C301.pdf"
			(at 0 0 180)
			(layer "F.Fab")
			(hide yes)
			(effects
				(font
					(size 1.27 1.27)
					(thickness 0.15)
				)
			)
		)
		(property "MPN" "ERJ2GE0R00X"
			(at 0 0 180)
			(unlocked yes)
			(layer "F.Fab")
			(hide yes)
			(effects
				(font
					(size 1 1)
					(thickness 0.15)
				)
			)
		)
		(property "Manufacturer" "Panasonic"
			(at 0 0 180)
			(unlocked yes)
			(layer "F.Fab")
			(hide yes)
			(effects
				(font
					(size 1 1)
					(thickness 0.15)
				)
			)
		)
		(property "License" "Apache-2.0"
			(at 0 0 180)
			(unlocked yes)
			(layer "F.Fab")
			(hide yes)
			(effects
				(font
					(size 1 1)
					(thickness 0.15)
				)
			)
		)
		(property "Author" "Antmicro"
			(at 0 0 180)
			(unlocked yes)
			(layer "F.Fab")
			(hide yes)
			(effects
				(font
					(size 1 1)
					(thickness 0.15)
				)
			)
		)
		(property "Val" "0R"
			(at 0 0 180)
			(unlocked yes)
			(layer "F.Fab")
			(hide yes)
			(effects
				(font
					(size 1 1)
					(thickness 0.15)
				)
			)
		)
		(property "Tolerance" "~"
			(at 0 0 180)
			(unlocked yes)
			(layer "F.Fab")
			(hide yes)
			(effects
				(font
					(size 1 1)
					(thickness 0.15)
				)
			)
		)
		(property "Current" "1A"
			(at 0 0 180)
			(unlocked yes)
			(layer "F.Fab")
			(hide yes)
			(effects
				(font
					(size 1 1)
					(thickness 0.15)
				)
			)
		)
		(sheetname "/Compute module/")
		(sheetfile "compute-module.kicad_sch")
		(attr smd exclude_from_pos_files exclude_from_bom dnp)
		(fp_rect
			(start -0.925 -0.47)
			(end 0.925 0.47)
			(stroke
				(width 0.05)
				(type default)
			)
			(fill no)
			(layer "F.CrtYd")
		)
		(fp_rect
			(start -0.5 -0.25)
			(end 0.5 0.25)
			(stroke
				(width 0.15)
				(type solid)
			)
			(fill no)
			(layer "F.Fab")
		)
		(fp_text user "${REFERENCE}"
			(at -0.95 3.168 180)
			(layer "F.Fab")
			(effects
				(font
					(size 0.7 0.7)
					(thickness 0.15)
				)
				(justify left bottom)
			)
		)
		(fp_text user "Author: Antmicro"
			(at -0.95 4.169 180)
			(layer "F.Fab")
			(effects
				(font
					(size 0.7 0.7)
					(thickness 0.15)
				)
				(justify left bottom)
			)
		)
		(fp_text user "License: Apache-2.0"
			(at -0.95 5.169 180)
			(layer "F.Fab")
			(effects
				(font
					(size 0.7 0.7)
					(thickness 0.15)
				)
				(justify left bottom)
			)
		)
		(pad "1" smd roundrect
			(at -0.48 0 180)
			(size 0.59 0.64)
			(layers "F.Cu" "F.Mask" "F.Paste")
			(roundrect_rratio 0.25)
			(net 3 "GND")
			(pintype "passive")
		)
		(pad "2" smd roundrect
			(at 0.48 0 180)
			(size 0.59 0.64)
			(layers "F.Cu" "F.Mask" "F.Paste")
			(roundrect_rratio 0.25)
			(net 216 "/Compute module/~{EEPROM_WP}")
			(pintype "passive")
		)
	)
	(footprint "antmicro-footprints:TP_SMD_0.75mm"
		(layer "F.Cu")
		(at 120 118.3 180)
		(property "Reference" "TP501"
			(at -0.955 -1.455 0)
			(layer "F.SilkS")
			(effects
				(font
					(size 0.7 0.7)
					(thickness 0.15)
				)
				(justify right bottom)
			)
		)
		(property "Value" "TP_0.75mm_SMD"
			(at 0 1.2 0)
			(layer "F.Fab")
			(effects
				(font
					(size 0.7 0.7)
					(thickness 0.15)
				)
				(justify right bottom)
			)
		)
		(property "MPN" ""
			(at 0 0 180)
			(unlocked yes)
			(layer "F.Fab")
			(hide yes)
			(effects
				(font
					(size 1 1)
					(thickness 0.15)
				)
			)
		)
		(property "Manufacturer" ""
			(at 0 0 180)
			(unlocked yes)
			(layer "F.Fab")
			(hide yes)
			(effects
				(font
					(size 1 1)
					(thickness 0.15)
				)
			)
		)
		(property "Author" "Antmicro"
			(at 0 0 180)
			(unlocked yes)
			(layer "F.Fab")
			(hide yes)
			(effects
				(font
					(size 1 1)
					(thickness 0.15)
				)
			)
		)
		(property "License" "Apache-2.0"
			(at 0 0 180)
			(unlocked yes)
			(layer "F.Fab")
			(hide yes)
			(effects
				(font
					(size 1 1)
					(thickness 0.15)
				)
			)
		)
		(sheetname "/NVMe & microSD/")
		(sheetfile "nvme-micro-sd.kicad_sch")
		(attr exclude_from_pos_files exclude_from_bom)
		(fp_circle
			(center 0 0)
			(end 0.475 0)
			(stroke
				(width 0.05)
				(type default)
			)
			(fill no)
			(layer "F.CrtYd")
		)
		(fp_text user "License: Apache-2.0"
			(at -0.4 5.101 180)
			(layer "F.Fab")
			(effects
				(font
					(size 0.7 0.7)
					(thickness 0.15)
				)
				(justify left bottom)
			)
		)
		(fp_text user "${REFERENCE}"
			(at -0.4 2.7 180)
			(layer "F.Fab")
			(effects
				(font
					(size 0.7 0.7)
					(thickness 0.15)
				)
				(justify left bottom)
			)
		)
		(fp_text user "Author: Antmicro"
			(at -0.4 3.901 180)
			(layer "F.Fab")
			(effects
				(font
					(size 0.7 0.7)
					(thickness 0.15)
				)
				(justify left bottom)
			)
		)
		(pad "1" smd circle
			(at 0 0 180)
			(size 0.75 0.75)
			(layers "F.Cu" "F.Mask")
			(net 178 "Net-(J501-SUSCLK)")
			(pinfunction "1")
			(pintype "passive")
		)
	)
	(footprint "antmicro-footprints:C_0402_1005Metric"
		(layer "F.Cu")
		(at 66.917962 169.4165 180)
		(descr "Capacitor SMD 0402")
		(tags "capacitor SMD 0402")
		(property "Reference" "C804"
			(at 6.762037 -3.158819 0)
			(layer "F.SilkS")
			(effects
				(font
					(size 0.7 0.7)
					(thickness 0.15)
				)
				(justify right bottom)
			)
		)
		(property "Value" "C_100n_0402"
			(at -1.022927 2.155213 0)
			(layer "F.Fab")
			(effects
				(font
					(size 0.7 0.7)
					(thickness 0.15)
				)
				(justify right bottom)
			)
		)
		(property "Datasheet" "https://www.murata.com/products/productdetail?partno=GRM155R61H104KE14%23"
			(at 0 0 180)
			(layer "F.Fab")
			(hide yes)
			(effects
				(font
					(size 1.27 1.27)
					(thickness 0.15)
				)
			)
		)
		(property "MPN" "GRM155R61H104KE14D"
			(at 0 0 180)
			(unlocked yes)
			(layer "F.Fab")
			(hide yes)
			(effects
				(font
					(size 1 1)
					(thickness 0.15)
				)
			)
		)
		(property "Manufacturer" "Murata"
			(at 0 0 180)
			(unlocked yes)
			(layer "F.Fab")
			(hide yes)
			(effects
				(font
					(size 1 1)
					(thickness 0.15)
				)
			)
		)
		(property "License" "Apache-2.0"
			(at 0 0 180)
			(unlocked yes)
			(layer "F.Fab")
			(hide yes)
			(effects
				(font
					(size 1 1)
					(thickness 0.15)
				)
			)
		)
		(property "Author" "Antmicro"
			(at 0 0 180)
			(unlocked yes)
			(layer "F.Fab")
			(hide yes)
			(effects
				(font
					(size 1 1)
					(thickness 0.15)
				)
			)
		)
		(property "Val" "100n"
			(at 0 0 180)
			(unlocked yes)
			(layer "F.Fab")
			(hide yes)
			(effects
				(font
					(size 1 1)
					(thickness 0.15)
				)
			)
		)
		(property "Voltage" "50V"
			(at 0 0 180)
			(unlocked yes)
			(layer "F.Fab")
			(hide yes)
			(effects
				(font
					(size 1 1)
					(thickness 0.15)
				)
			)
		)
		(property "Dielectric" "X5R"
			(at 0 0 180)
			(unlocked yes)
			(layer "F.Fab")
			(hide yes)
			(effects
				(font
					(size 1 1)
					(thickness 0.15)
				)
			)
		)
		(sheetname "/Peripherals/")
		(sheetfile "peripherals.kicad_sch")
		(attr smd)
		(fp_rect
			(start -0.925 -0.47)
			(end 0.925 0.47)
			(stroke
				(width 0.05)
				(type default)
			)
			(fill no)
			(layer "F.CrtYd")
		)
		(fp_line
			(start 0.504 0.248)
			(end -0.494 0.248)
			(stroke
				(width 0.15)
				(type solid)
			)
			(layer "F.Fab")
		)
		(fp_line
			(start 0.504 -0.25)
			(end 0.504 0.248)
			(stroke
				(width 0.15)
				(type solid)
			)
			(layer "F.Fab")
		)
		(fp_line
			(start -0.494 0.248)
			(end -0.494 -0.25)
			(stroke
				(width 0.15)
				(type solid)
			)
			(layer "F.Fab")
		)
		(fp_line
			(start -0.494 -0.25)
			(end 0.504 -0.25)
			(stroke
				(width 0.15)
				(type solid)
			)
			(layer "F.Fab")
		)
		(fp_text user "License: Apache-2.0"
			(at -0.939 5.799 180)
			(layer "F.Fab")
			(effects
				(font
					(size 0.7 0.7)
					(thickness 0.15)
				)
				(justify left bottom)
			)
		)
		(fp_text user "${REFERENCE}"
			(at -0.939 4.599 180)
			(layer "F.Fab")
			(effects
				(font
					(size 0.7 0.7)
					(thickness 0.15)
				)
				(justify left bottom)
			)
		)
		(fp_text user "Author: Antmicro"
			(at -0.939 3.399 180)
			(layer "F.Fab")
			(effects
				(font
					(size 0.7 0.7)
					(thickness 0.15)
				)
				(justify left bottom)
			)
		)
		(pad "1" smd roundrect
			(at -0.48 0 180)
			(size 0.59 0.64)
			(layers "F.Cu" "F.Mask" "F.Paste")
			(roundrect_rratio 0.25)
			(net 501 "Net-(U801-V_{DD(UP)})")
			(pintype "passive")
		)
		(pad "2" smd roundrect
			(at 0.48 0 180)
			(size 0.59 0.64)
			(layers "F.Cu" "F.Mask" "F.Paste")
			(roundrect_rratio 0.25)
			(net 3 "GND")
			(pintype "passive")
		)
	)
)
